# BASEBOARD_FAB2 (Tioga Pass) — schematic netlist excerpt (pin names and nets, part order shuffled) for the footprints in the layout excerpt that follows; sources: Cadence DE-HDL packaged netlist, KiCad conversion of Wiwynn_Tioga_Pass_MB.brd

R6P13  RES  42.2 1.0% EMPTY  pkg 0402  page 103 : A = CLK_100M_CPU0_BCLK2_DP ; B = GND
C1M12  CAP  0.22UF 16V 10% X7R  pkg 0402  page 106 : A = P3E_CPU0_PE3_OCP_TXP<12> ; B = P3E_OCP_CPU0_PE3_C_TXP<12>
R6L4  RES  1.0M 1% EMPTY  pkg 0402  page 222 : A = P3V3 ; B = FM_PVTT_DEF_EN_R

(kicad_pcb
	(version 20260206)
	(generator "pcbnew")
	(generator_version "10.0")
	(general
		(thickness 1.6)
		(legacy_teardrops no)
	)
	(paper "A4")
	(title_block
		(title "Wiwynn_Tioga_Pass_MB.brd")
		(comment 1 "Tioga Pass / footprints 3287-3289 of 4770")
	)
	(layers
		(0 "F.Cu" signal "TOP")
		(4 "In1.Cu" signal "L2GND")
		(6 "In2.Cu" signal "L3")
		(8 "In3.Cu" signal "L4GND")
		(10 "In4.Cu" signal "L5")
		(12 "In5.Cu" signal "L6GND")
		(14 "In6.Cu" signal "L7VCC")
		(16 "In7.Cu" signal "L8VCC")
		(18 "In8.Cu" signal "L9GND")
		(20 "In9.Cu" signal "L10")
		(22 "In10.Cu" signal "L11GND")
		(24 "In11.Cu" signal "L12")
		(26 "In12.Cu" signal "L13GND")
		(2 "B.Cu" signal "BOTTOM")
		(9 "F.Adhes" user "F.Adhesive")
		(11 "B.Adhes" user "B.Adhesive")
		(13 "F.Paste" user "Package Geometry/Pastemask Top")
		(15 "B.Paste" user "Package Geometry/Pastemask Bottom")
		(5 "F.SilkS" user "Ref Des/Silkscreen Top")
		(7 "B.SilkS" user "Ref Des/Silkscreen Bottom")
		(1 "F.Mask" user "Board Geometry/Soldermask Top")
		(3 "B.Mask" user "Board Geometry/Soldermask Bottom")
		(17 "Dwgs.User" user "User.Drawings")
		(19 "Cmts.User" user "User.Comments")
		(21 "Eco1.User" user "User.Eco1")
		(23 "Eco2.User" user "User.Eco2")
		(25 "Edge.Cuts" user "Board Geometry/Outline")
		(27 "Margin" user)
		(31 "F.CrtYd" user "Package Geometry/Place Bound Top")
		(29 "B.CrtYd" user "Package Geometry/Place Bound Bottom")
		(35 "F.Fab" user "Ref Des/Assembly Top")
		(33 "B.Fab" user "Ref Des/Assembly Bottom")
	)
	(footprint ""
		(layer "B.Cu")
		(at 456.692 -116.49202)
		(property "Reference" "C1M12"
			(at 0 0 0)
			(layer "B.SilkS")
			(hide yes)
			(effects
				(font
					(size 1.27 1.27)
				)
				(justify mirror)
			)
		)
		(property "Value" ""
			(at 0 0 0)
			(layer "B.Fab")
			(effects
				(font
					(size 1.27 1.27)
				)
				(justify mirror)
			)
		)
		(duplicate_pad_numbers_are_jumpers no)
		(fp_rect
			(start -0.3048 0.9906)
			(end 0.3048 -0.1016)
			(stroke
				(width 0)
				(type default)
			)
			(fill no)
			(layer "B.CrtYd")
		)
		(fp_line
			(start -0.3048 -0.1016)
			(end 0.3048 -0.1016)
			(stroke
				(width 0.1)
				(type default)
			)
			(layer "B.Fab")
		)
		(fp_line
			(start -0.3048 0.9906)
			(end -0.3048 -0.1016)
			(stroke
				(width 0.1)
				(type default)
			)
			(layer "B.Fab")
		)
		(fp_line
			(start 0.3048 -0.1016)
			(end 0.3048 0.9906)
			(stroke
				(width 0.1)
				(type default)
			)
			(layer "B.Fab")
		)
		(fp_line
			(start 0.3048 0.9906)
			(end -0.3048 0.9906)
			(stroke
				(width 0.1)
				(type default)
			)
			(layer "B.Fab")
		)
		(pad "1" smd rect
			(at 0 0 180)
			(size 0.508 0.508)
			(layers "B.Cu" "B.Mask" "B.Paste")
			(net "P3E_CPU0_PE3_OCP_TXP<12>")
		)
		(pad "2" smd rect
			(at 0 0.889 180)
			(size 0.508 0.508)
			(layers "B.Cu" "B.Mask" "B.Paste")
			(net "P3E_OCP_CPU0_PE3_C_TXP<12>")
		)
		(zone
			(layer "B.Cu")
			(hatch none 0.5)
			(connect_pads
				(clearance 0)
			)
			(min_thickness 0.25)
			(keepout
				(tracks not_allowed)
				(vias allowed)
				(pads allowed)
				(copperpour not_allowed)
				(footprints allowed)
			)
			(placement
				(enabled no)
				(sheetname "")
			)
			(fill
				(thermal_gap 0.5)
				(thermal_bridge_width 0.5)
				(island_removal_mode 0)
			)
			(polygon
				(pts
					(xy 456.438 -115.85702) (xy 456.946 -115.85702) (xy 456.946 -116.23802) (xy 456.438 -116.23802)
				)
			)
		)
		(zone
			(layer "B.Cu")
			(hatch none 0.5)
			(connect_pads
				(clearance 0)
			)
			(min_thickness 0.25)
			(keepout
				(tracks allowed)
				(vias not_allowed)
				(pads allowed)
				(copperpour not_allowed)
				(footprints allowed)
			)
			(placement
				(enabled no)
				(sheetname "")
			)
			(fill
				(thermal_gap 0.5)
				(thermal_bridge_width 0.5)
				(island_removal_mode 0)
			)
			(polygon
				(pts
					(xy 456.438 -115.85702) (xy 456.946 -115.85702) (xy 456.946 -116.23802) (xy 456.438 -116.23802)
				)
			)
		)
	)
	(footprint ""
		(layer "B.Cu")
		(at 176.25568 -81.407 -90)
		(property "Reference" "R6P13"
			(at 0 0 90)
			(layer "B.SilkS")
			(hide yes)
			(effects
				(font
					(size 1.27 1.27)
				)
				(justify mirror)
			)
		)
		(property "Value" ""
			(at 0 0 90)
			(layer "B.Fab")
			(effects
				(font
					(size 1.27 1.27)
				)
				(justify mirror)
			)
		)
		(duplicate_pad_numbers_are_jumpers no)
		(fp_poly
			(pts
				(xy 0.2794 -0.1016) (xy -0.2794 -0.1016) (xy -0.2794 0.9906) (xy 0.2794 0.9906)
			)
			(stroke
				(width 0)
				(type default)
			)
			(fill no)
			(layer "B.CrtYd")
		)
		(fp_line
			(start -0.2794 0.9906)
			(end -0.2794 -0.1016)
			(stroke
				(width 0.1)
				(type default)
			)
			(layer "B.Fab")
		)
		(fp_line
			(start 0.2794 0.9906)
			(end -0.2794 0.9906)
			(stroke
				(width 0.1)
				(type default)
			)
			(layer "B.Fab")
		)
		(fp_line
			(start -0.2794 -0.1016)
			(end 0.2794 -0.1016)
			(stroke
				(width 0.1)
				(type default)
			)
			(layer "B.Fab")
		)
		(fp_line
			(start 0.2794 -0.1016)
			(end 0.2794 0.9906)
			(stroke
				(width 0.1)
				(type default)
			)
			(layer "B.Fab")
		)
		(pad "1" smd rect
			(at 0 0 90)
			(size 0.508 0.508)
			(layers "B.Cu" "B.Mask" "B.Paste")
			(net "CLK_100M_CPU0_BCLK2_DP")
		)
		(pad "2" smd rect
			(at 0 0.889 90)
			(size 0.508 0.508)
			(layers "B.Cu" "B.Mask" "B.Paste")
			(net "GND")
		)
		(zone
			(layer "B.Cu")
			(hatch none 0.5)
			(connect_pads
				(clearance 0)
			)
			(min_thickness 0.25)
			(keepout
				(tracks not_allowed)
				(vias allowed)
				(pads allowed)
				(copperpour not_allowed)
				(footprints allowed)
			)
			(placement
				(enabled no)
				(sheetname "")
			)
			(fill
				(thermal_gap 0.5)
				(thermal_bridge_width 0.5)
				(island_removal_mode 0)
			)
			(polygon
				(pts
					(xy 175.62068 -81.153) (xy 175.62068 -81.661) (xy 176.00168 -81.661) (xy 176.00168 -81.153)
				)
			)
		)
		(zone
			(layer "B.Cu")
			(hatch none 0.5)
			(connect_pads
				(clearance 0)
			)
			(min_thickness 0.25)
			(keepout
				(tracks allowed)
				(vias not_allowed)
				(pads allowed)
				(copperpour not_allowed)
				(footprints allowed)
			)
			(placement
				(enabled no)
				(sheetname "")
			)
			(fill
				(thermal_gap 0.5)
				(thermal_bridge_width 0.5)
				(island_removal_mode 0)
			)
			(polygon
				(pts
					(xy 176.00168 -81.153) (xy 176.00168 -81.661) (xy 175.62068 -81.661) (xy 175.62068 -81.153)
				)
			)
		)
	)
	(footprint ""
		(layer "B.Cu")
		(at 184.658 -153.416)
		(property "Reference" "R6L4"
			(at 0 0 0)
			(layer "B.SilkS")
			(hide yes)
			(effects
				(font
					(size 1.27 1.27)
				)
				(justify mirror)
			)
		)
		(property "Value" ""
			(at 0 0 0)
			(layer "B.Fab")
			(effects
				(font
					(size 1.27 1.27)
				)
				(justify mirror)
			)
		)
		(duplicate_pad_numbers_are_jumpers no)
		(fp_rect
			(start 0.2794 -0.1016)
			(end -0.2794 0.9906)
			(stroke
				(width 0)
				(type default)
			)
			(fill no)
			(layer "B.CrtYd")
		)
		(fp_line
			(start -0.2794 -0.1016)
			(end 0.2794 -0.1016)
			(stroke
				(width 0.1)
				(type default)
			)
			(layer "B.Fab")
		)
		(fp_line
			(start -0.2794 0.9906)
			(end -0.2794 -0.1016)
			(stroke
				(width 0.1)
				(type default)
			)
			(layer "B.Fab")
		)
		(fp_line
			(start 0.2794 -0.1016)
			(end 0.2794 0.9906)
			(stroke
				(width 0.1)
				(type default)
			)
			(layer "B.Fab")
		)
		(fp_line
			(start 0.2794 0.9906)
			(end -0.2794 0.9906)
			(stroke
				(width 0.1)
				(type default)
			)
			(layer "B.Fab")
		)
		(pad "1" smd rect
			(at 0 0 180)
			(size 0.508 0.508)
			(layers "B.Cu" "B.Mask" "B.Paste")
			(net "P3V3")
		)
		(pad "2" smd rect
			(at 0 0.889 180)
			(size 0.508 0.508)
			(layers "B.Cu" "B.Mask" "B.Paste")
			(net "FM_PVTT_DEF_EN_R")
		)
		(zone
			(layer "B.Cu")
			(hatch none 0.5)
			(connect_pads
				(clearance 0)
			)
			(min_thickness 0.25)
			(keepout
				(tracks allowed)
				(vias not_allowed)
				(pads allowed)
				(copperpour not_allowed)
				(footprints allowed)
			)
			(placement
				(enabled no)
				(sheetname "")
			)
			(fill
				(thermal_gap 0.5)
				(thermal_bridge_width 0.5)
				(island_removal_mode 0)
			)
			(polygon
				(pts
					(xy 184.912 -153.162) (xy 184.404 -153.162) (xy 184.404 -152.781) (xy 184.912 -152.781)
				)
			)
		)
		(zone
			(layer "B.Cu")
			(hatch none 0.5)
			(connect_pads
				(clearance 0)
			)
			(min_thickness 0.25)
			(keepout
				(tracks not_allowed)
				(vias allowed)
				(pads allowed)
				(copperpour not_allowed)
				(footprints allowed)
			)
			(placement
				(enabled no)
				(sheetname "")
			)
			(fill
				(thermal_gap 0.5)
				(thermal_bridge_width 0.5)
				(island_removal_mode 0)
			)
			(polygon
				(pts
					(xy 184.912 -153.162) (xy 184.404 -153.162) (xy 184.404 -152.781) (xy 184.912 -152.781)
				)
			)
		)
	)
)
